# T6G (Grand Teton) — schematic netlist excerpt (pin names and nets, part order shuffled) for the footprints in the layout excerpt that follows; sources: Cadence DE-HDL packaged netlist, KiCad conversion of 04192023_DAF0TMB3IC0_F0TG_MB_C_brd_V02_OCP.brd

R5012  Q_RES  1K 1% EMPTY  pkg 0402LF  page 159 : A = PVDD11_S3_P1 ; B = I3C_SPD_DDRGL_CPU1_LVC1_SCL
PC406_3  Q_CAP  1UF 25V 10% X6S  pkg C0402  page 219 : A = SW_P12V_AUX_PVDDCR_CPU1_P1_FLT ; B = GND

(kicad_pcb
	(version 20260206)
	(generator "pcbnew")
	(generator_version "10.0")
	(general
		(thickness 1.6)
		(legacy_teardrops no)
	)
	(paper "A4")
	(title_block
		(title "04192023_DAF0TMB3IC0_F0TG_MB_C_brd_V02_OCP.brd")
		(comment 1 "Grand Teton / footprints 1695-1696 of 8354")
	)
	(layers
		(0 "F.Cu" signal "TOP")
		(4 "In1.Cu" signal "GND")
		(6 "In2.Cu" signal "IN1")
		(8 "In3.Cu" signal "GND1")
		(10 "In4.Cu" signal "IN2")
		(12 "In5.Cu" signal "GND2")
		(14 "In6.Cu" signal "IN3")
		(16 "In7.Cu" signal "GND3")
		(18 "In8.Cu" signal "VCC")
		(20 "In9.Cu" signal "VCC1")
		(22 "In10.Cu" signal "GND4")
		(24 "In11.Cu" signal "IN4")
		(26 "In12.Cu" signal "GND5")
		(28 "In13.Cu" signal "IN5")
		(30 "In14.Cu" signal "GND6")
		(32 "In15.Cu" signal "IN6")
		(34 "In16.Cu" signal "GND7")
		(2 "B.Cu" signal "BOTTOM")
		(9 "F.Adhes" user "F.Adhesive")
		(11 "B.Adhes" user "B.Adhesive")
		(13 "F.Paste" user "Package Geometry/Pastemask Top")
		(15 "B.Paste" user "Package Geometry/Pastemask Bottom")
		(5 "F.SilkS" user "Ref Des/Silkscreen Top")
		(7 "B.SilkS" user "Ref Des/Silkscreen Bottom")
		(1 "F.Mask" user "Board Geometry/Soldermask Top")
		(3 "B.Mask" user "Board Geometry/Soldermask Bottom")
		(17 "Dwgs.User" user "User.Drawings")
		(19 "Cmts.User" user "User.Comments")
		(21 "Eco1.User" user "User.Eco1")
		(23 "Eco2.User" user "User.Eco2")
		(25 "Edge.Cuts" user "Board Geometry/Outline")
		(27 "Margin" user)
		(31 "F.CrtYd" user "Package Geometry/Place Bound Top")
		(29 "B.CrtYd" user "Package Geometry/Place Bound Bottom")
		(35 "F.Fab" user "Ref Des/Assembly Top")
		(33 "B.Fab" user "Ref Des/Assembly Bottom")
	)
	(footprint ""
		(layer "F.Cu")
		(at 182.404766 -168.317418 -90)
		(property "Reference" "R5012"
			(at 0 0 270)
			(layer "F.SilkS")
			(hide yes)
			(effects
				(font
					(size 1.27 1.27)
				)
			)
		)
		(property "Value" ""
			(at 0 0 270)
			(layer "F.Fab")
			(effects
				(font
					(size 1.27 1.27)
				)
			)
		)
		(duplicate_pad_numbers_are_jumpers no)
		(fp_line
			(start -0.7874 0.4064)
			(end -0.7874 -0.4064)
			(stroke
				(width 0.1524)
				(type default)
			)
			(layer "F.SilkS")
		)
		(fp_line
			(start 0.7874 0.4064)
			(end -0.7874 0.4064)
			(stroke
				(width 0.1524)
				(type default)
			)
			(layer "F.SilkS")
		)
		(fp_line
			(start -0.7874 -0.4064)
			(end 0.7874 -0.4064)
			(stroke
				(width 0.1524)
				(type default)
			)
			(layer "F.SilkS")
		)
		(fp_line
			(start 0.7874 -0.4064)
			(end 0.7874 0.4064)
			(stroke
				(width 0.1524)
				(type default)
			)
			(layer "F.SilkS")
		)
		(fp_line
			(start -0.67945 0.3048)
			(end -0.67945 -0.305054)
			(stroke
				(width 0.1)
				(type default)
			)
			(layer "F.Fab")
		)
		(fp_line
			(start -0.12065 0.3048)
			(end -0.67945 0.3048)
			(stroke
				(width 0.1)
				(type default)
			)
			(layer "F.Fab")
		)
		(fp_line
			(start 0.120396 0.3048)
			(end 0.120396 0.2794)
			(stroke
				(width 0.1)
				(type default)
			)
			(layer "F.Fab")
		)
		(fp_line
			(start 0.67945 0.3048)
			(end 0.120396 0.3048)
			(stroke
				(width 0.1)
				(type default)
			)
			(layer "F.Fab")
		)
		(fp_line
			(start -0.12065 0.2794)
			(end -0.12065 0.3048)
			(stroke
				(width 0.1)
				(type default)
			)
			(layer "F.Fab")
		)
		(fp_line
			(start 0.120396 0.2794)
			(end -0.12065 0.2794)
			(stroke
				(width 0.1)
				(type default)
			)
			(layer "F.Fab")
		)
		(fp_line
			(start -0.12065 -0.2794)
			(end 0.12065 -0.2794)
			(stroke
				(width 0.1)
				(type default)
			)
			(layer "F.Fab")
		)
		(fp_line
			(start 0.12065 -0.2794)
			(end 0.12065 -0.3048)
			(stroke
				(width 0.1)
				(type default)
			)
			(layer "F.Fab")
		)
		(fp_line
			(start 0.12065 -0.3048)
			(end 0.67945 -0.3048)
			(stroke
				(width 0.1)
				(type default)
			)
			(layer "F.Fab")
		)
		(fp_line
			(start 0.67945 -0.3048)
			(end 0.67945 0.3048)
			(stroke
				(width 0.1)
				(type default)
			)
			(layer "F.Fab")
		)
		(fp_line
			(start -0.67945 -0.305054)
			(end -0.12065 -0.305054)
			(stroke
				(width 0.1)
				(type default)
			)
			(layer "F.Fab")
		)
		(fp_line
			(start -0.12065 -0.305054)
			(end -0.12065 -0.2794)
			(stroke
				(width 0.1)
				(type default)
			)
			(layer "F.Fab")
		)
		(pad "1" smd circle
			(at -0.40005 0 270)
			(size 0 0)
			(layers "F.Cu" "F.Mask" "F.Paste")
			(net "PVDD11_S3_P1")
		)
		(pad "2" smd circle
			(at 0.40005 0 270)
			(size 0 0)
			(layers "F.Cu" "F.Mask" "F.Paste")
			(net "I3C_SPD_DDRGL_CPU1_LVC1_SCL")
		)
	)
	(footprint ""
		(layer "F.Cu")
		(at 74.04354 -335.099406 -90)
		(property "Reference" "PC406_3"
			(at 0 0 270)
			(layer "F.SilkS")
			(hide yes)
			(effects
				(font
					(size 1.27 1.27)
				)
			)
		)
		(property "Value" ""
			(at 0 0 270)
			(layer "F.Fab")
			(effects
				(font
					(size 1.27 1.27)
				)
			)
		)
		(duplicate_pad_numbers_are_jumpers no)
		(fp_line
			(start -0.7874 0.4064)
			(end -0.7874 -0.4064)
			(stroke
				(width 0.1524)
				(type default)
			)
			(layer "F.SilkS")
		)
		(fp_line
			(start 0.7874 0.4064)
			(end -0.7874 0.4064)
			(stroke
				(width 0.1524)
				(type default)
			)
			(layer "F.SilkS")
		)
		(fp_line
			(start -0.7874 -0.4064)
			(end 0.7874 -0.4064)
			(stroke
				(width 0.1524)
				(type default)
			)
			(layer "F.SilkS")
		)
		(fp_line
			(start 0.7874 -0.4064)
			(end 0.7874 0.4064)
			(stroke
				(width 0.1524)
				(type default)
			)
			(layer "F.SilkS")
		)
		(fp_line
			(start -0.67945 0.3048)
			(end -0.67945 -0.305054)
			(stroke
				(width 0.1)
				(type default)
			)
			(layer "F.Fab")
		)
		(fp_line
			(start -0.12065 0.3048)
			(end -0.67945 0.3048)
			(stroke
				(width 0.1)
				(type default)
			)
			(layer "F.Fab")
		)
		(fp_line
			(start 0.120396 0.3048)
			(end 0.120396 0.2794)
			(stroke
				(width 0.1)
				(type default)
			)
			(layer "F.Fab")
		)
		(fp_line
			(start 0.67945 0.3048)
			(end 0.120396 0.3048)
			(stroke
				(width 0.1)
				(type default)
			)
			(layer "F.Fab")
		)
		(fp_line
			(start -0.12065 0.2794)
			(end -0.12065 0.3048)
			(stroke
				(width 0.1)
				(type default)
			)
			(layer "F.Fab")
		)
		(fp_line
			(start 0.120396 0.2794)
			(end -0.12065 0.2794)
			(stroke
				(width 0.1)
				(type default)
			)
			(layer "F.Fab")
		)
		(fp_line
			(start -0.12065 -0.2794)
			(end 0.12065 -0.2794)
			(stroke
				(width 0.1)
				(type default)
			)
			(layer "F.Fab")
		)
		(fp_line
			(start 0.12065 -0.2794)
			(end 0.12065 -0.3048)
			(stroke
				(width 0.1)
				(type default)
			)
			(layer "F.Fab")
		)
		(fp_line
			(start 0.12065 -0.3048)
			(end 0.67945 -0.3048)
			(stroke
				(width 0.1)
				(type default)
			)
			(layer "F.Fab")
		)
		(fp_line
			(start 0.67945 -0.3048)
			(end 0.67945 0.3048)
			(stroke
				(width 0.1)
				(type default)
			)
			(layer "F.Fab")
		)
		(fp_line
			(start -0.67945 -0.305054)
			(end -0.12065 -0.305054)
			(stroke
				(width 0.1)
				(type default)
			)
			(layer "F.Fab")
		)
		(fp_line
			(start -0.12065 -0.305054)
			(end -0.12065 -0.2794)
			(stroke
				(width 0.1)
				(type default)
			)
			(layer "F.Fab")
		)
		(pad "1" smd circle
			(at -0.40005 0 270)
			(size 0 0)
			(layers "F.Cu" "F.Mask" "F.Paste")
			(net "SW_P12V_AUX_PVDDCR_CPU1_P1_FLT")
		)
		(pad "2" smd circle
			(at 0.40005 0 270)
			(size 0 0)
			(layers "F.Cu" "F.Mask" "F.Paste")
			(net "GND")
		)
	)
)
